# T6G (Grand Teton) — schematic netlist excerpt (pin names and nets, part order shuffled) for the footprints in the layout excerpt that follows; sources: Cadence DE-HDL packaged netlist, KiCad conversion of 04192023_DAF0TMB3IC0_F0TG_MB_C_brd_V02_OCP.brd

R3574  Q_RES  10 1% CHIP  pkg 0402LF  page 237 : A = P3V3 ; B = VSENSE_P12V_INA230_4_INP
C84  Q_CAP  0.1UF 25V 10% X7R  pkg 0402  page 183 : A = P3V3_9ZXL045_P1_VDDR ; B = GND
C6512  Q_CAP_DIFFBUS  DIFF BUS_0.22UF 6.3V 20% X6S  pkg C0201  page 275 : \1\ = P5E_CPU0_P0_TX_BUF_C_DN<5> ; \2\ = P5E_CPU0_P0_TX_BUF_DN<5>

(kicad_pcb
	(version 20260206)
	(generator "pcbnew")
	(generator_version "10.0")
	(general
		(thickness 1.6)
		(legacy_teardrops no)
	)
	(paper "A4")
	(title_block
		(title "04192023_DAF0TMB3IC0_F0TG_MB_C_brd_V02_OCP.brd")
		(comment 1 "Grand Teton / footprints 4515-4517 of 8354")
	)
	(layers
		(0 "F.Cu" signal "TOP")
		(4 "In1.Cu" signal "GND")
		(6 "In2.Cu" signal "IN1")
		(8 "In3.Cu" signal "GND1")
		(10 "In4.Cu" signal "IN2")
		(12 "In5.Cu" signal "GND2")
		(14 "In6.Cu" signal "IN3")
		(16 "In7.Cu" signal "GND3")
		(18 "In8.Cu" signal "VCC")
		(20 "In9.Cu" signal "VCC1")
		(22 "In10.Cu" signal "GND4")
		(24 "In11.Cu" signal "IN4")
		(26 "In12.Cu" signal "GND5")
		(28 "In13.Cu" signal "IN5")
		(30 "In14.Cu" signal "GND6")
		(32 "In15.Cu" signal "IN6")
		(34 "In16.Cu" signal "GND7")
		(2 "B.Cu" signal "BOTTOM")
		(9 "F.Adhes" user "F.Adhesive")
		(11 "B.Adhes" user "B.Adhesive")
		(13 "F.Paste" user "Package Geometry/Pastemask Top")
		(15 "B.Paste" user "Package Geometry/Pastemask Bottom")
		(5 "F.SilkS" user "Ref Des/Silkscreen Top")
		(7 "B.SilkS" user "Ref Des/Silkscreen Bottom")
		(1 "F.Mask" user "Board Geometry/Soldermask Top")
		(3 "B.Mask" user "Board Geometry/Soldermask Bottom")
		(17 "Dwgs.User" user "User.Drawings")
		(19 "Cmts.User" user "User.Comments")
		(21 "Eco1.User" user "User.Eco1")
		(23 "Eco2.User" user "User.Eco2")
		(25 "Edge.Cuts" user "Board Geometry/Outline")
		(27 "Margin" user)
		(31 "F.CrtYd" user "Package Geometry/Place Bound Top")
		(29 "B.CrtYd" user "Package Geometry/Place Bound Bottom")
		(35 "F.Fab" user "Ref Des/Assembly Top")
		(33 "B.Fab" user "Ref Des/Assembly Bottom")
	)
	(footprint ""
		(layer "F.Cu")
		(at 319.084706 -416.899344 -90)
		(property "Reference" "C6512"
			(at 0 0 270)
			(layer "F.SilkS")
			(hide yes)
			(effects
				(font
					(size 1.27 1.27)
				)
			)
		)
		(property "Value" ""
			(at 0 0 270)
			(layer "F.Fab")
			(effects
				(font
					(size 1.27 1.27)
				)
			)
		)
		(duplicate_pad_numbers_are_jumpers no)
		(fp_line
			(start -0.299974 0.150114)
			(end -0.299974 -0.150114)
			(stroke
				(width 0.1)
				(type default)
			)
			(layer "F.Fab")
		)
		(fp_line
			(start 0.299974 0.150114)
			(end -0.299974 0.150114)
			(stroke
				(width 0.1)
				(type default)
			)
			(layer "F.Fab")
		)
		(fp_line
			(start -0.299974 -0.150114)
			(end 0.299974 -0.150114)
			(stroke
				(width 0.1)
				(type default)
			)
			(layer "F.Fab")
		)
		(fp_line
			(start 0.299974 -0.150114)
			(end 0.299974 0.150114)
			(stroke
				(width 0.1)
				(type default)
			)
			(layer "F.Fab")
		)
		(pad "1" smd rect
			(at -0.2667 0 270)
			(size 0.3048 0.381)
			(layers "F.Cu" "F.Mask" "F.Paste")
			(net "P5E_CPU0_P0_TX_BUF_C_DN<5>")
		)
		(pad "2" smd rect
			(at 0.2667 0 270)
			(size 0.3048 0.381)
			(layers "F.Cu" "F.Mask" "F.Paste")
			(net "P5E_CPU0_P0_TX_BUF_DN<5>")
		)
	)
	(footprint ""
		(layer "F.Cu")
		(at 161.571686 -58.66765 180)
		(property "Reference" "R3574"
			(at 0 0 180)
			(layer "F.SilkS")
			(hide yes)
			(effects
				(font
					(size 1.27 1.27)
				)
			)
		)
		(property "Value" ""
			(at 0 0 180)
			(layer "F.Fab")
			(effects
				(font
					(size 1.27 1.27)
				)
			)
		)
		(duplicate_pad_numbers_are_jumpers no)
		(fp_line
			(start 0.7874 0.4064)
			(end -0.7874 0.4064)
			(stroke
				(width 0.1524)
				(type default)
			)
			(layer "F.SilkS")
		)
		(fp_line
			(start 0.7874 -0.4064)
			(end 0.7874 0.4064)
			(stroke
				(width 0.1524)
				(type default)
			)
			(layer "F.SilkS")
		)
		(fp_line
			(start -0.7874 0.4064)
			(end -0.7874 -0.4064)
			(stroke
				(width 0.1524)
				(type default)
			)
			(layer "F.SilkS")
		)
		(fp_line
			(start -0.7874 -0.4064)
			(end 0.7874 -0.4064)
			(stroke
				(width 0.1524)
				(type default)
			)
			(layer "F.SilkS")
		)
		(fp_line
			(start 0.67945 0.3048)
			(end 0.120396 0.3048)
			(stroke
				(width 0.1)
				(type default)
			)
			(layer "F.Fab")
		)
		(fp_line
			(start 0.67945 -0.3048)
			(end 0.67945 0.3048)
			(stroke
				(width 0.1)
				(type default)
			)
			(layer "F.Fab")
		)
		(fp_line
			(start 0.12065 -0.2794)
			(end 0.12065 -0.3048)
			(stroke
				(width 0.1)
				(type default)
			)
			(layer "F.Fab")
		)
		(fp_line
			(start 0.12065 -0.3048)
			(end 0.67945 -0.3048)
			(stroke
				(width 0.1)
				(type default)
			)
			(layer "F.Fab")
		)
		(fp_line
			(start 0.120396 0.3048)
			(end 0.120396 0.2794)
			(stroke
				(width 0.1)
				(type default)
			)
			(layer "F.Fab")
		)
		(fp_line
			(start 0.120396 0.2794)
			(end -0.12065 0.2794)
			(stroke
				(width 0.1)
				(type default)
			)
			(layer "F.Fab")
		)
		(fp_line
			(start -0.12065 0.3048)
			(end -0.67945 0.3048)
			(stroke
				(width 0.1)
				(type default)
			)
			(layer "F.Fab")
		)
		(fp_line
			(start -0.12065 0.2794)
			(end -0.12065 0.3048)
			(stroke
				(width 0.1)
				(type default)
			)
			(layer "F.Fab")
		)
		(fp_line
			(start -0.12065 -0.2794)
			(end 0.12065 -0.2794)
			(stroke
				(width 0.1)
				(type default)
			)
			(layer "F.Fab")
		)
		(fp_line
			(start -0.12065 -0.305054)
			(end -0.12065 -0.2794)
			(stroke
				(width 0.1)
				(type default)
			)
			(layer "F.Fab")
		)
		(fp_line
			(start -0.67945 0.3048)
			(end -0.67945 -0.305054)
			(stroke
				(width 0.1)
				(type default)
			)
			(layer "F.Fab")
		)
		(fp_line
			(start -0.67945 -0.305054)
			(end -0.12065 -0.305054)
			(stroke
				(width 0.1)
				(type default)
			)
			(layer "F.Fab")
		)
		(pad "1" smd circle
			(at -0.40005 0 180)
			(size 0 0)
			(layers "F.Cu" "F.Mask" "F.Paste")
			(net "P3V3")
		)
		(pad "2" smd circle
			(at 0.40005 0 180)
			(size 0 0)
			(layers "F.Cu" "F.Mask" "F.Paste")
			(net "VSENSE_P12V_INA230_4_INP")
		)
	)
	(footprint ""
		(layer "F.Cu")
		(at 106.934 -415.036 180)
		(property "Reference" "C84"
			(at 0 0 180)
			(layer "F.SilkS")
			(hide yes)
			(effects
				(font
					(size 1.27 1.27)
				)
			)
		)
		(property "Value" ""
			(at 0 0 180)
			(layer "F.Fab")
			(effects
				(font
					(size 1.27 1.27)
				)
			)
		)
		(duplicate_pad_numbers_are_jumpers no)
		(fp_line
			(start 0.7874 0.4064)
			(end -0.7874 0.4064)
			(stroke
				(width 0.1524)
				(type default)
			)
			(layer "F.SilkS")
		)
		(fp_line
			(start 0.7874 -0.4064)
			(end 0.7874 0.4064)
			(stroke
				(width 0.1524)
				(type default)
			)
			(layer "F.SilkS")
		)
		(fp_line
			(start -0.7874 0.4064)
			(end -0.7874 -0.4064)
			(stroke
				(width 0.1524)
				(type default)
			)
			(layer "F.SilkS")
		)
		(fp_line
			(start -0.7874 -0.4064)
			(end 0.7874 -0.4064)
			(stroke
				(width 0.1524)
				(type default)
			)
			(layer "F.SilkS")
		)
		(fp_line
			(start 0.67945 0.3048)
			(end 0.120396 0.3048)
			(stroke
				(width 0.1)
				(type default)
			)
			(layer "F.Fab")
		)
		(fp_line
			(start 0.67945 -0.3048)
			(end 0.67945 0.3048)
			(stroke
				(width 0.1)
				(type default)
			)
			(layer "F.Fab")
		)
		(fp_line
			(start 0.12065 -0.2794)
			(end 0.12065 -0.3048)
			(stroke
				(width 0.1)
				(type default)
			)
			(layer "F.Fab")
		)
		(fp_line
			(start 0.12065 -0.3048)
			(end 0.67945 -0.3048)
			(stroke
				(width 0.1)
				(type default)
			)
			(layer "F.Fab")
		)
		(fp_line
			(start 0.120396 0.3048)
			(end 0.120396 0.2794)
			(stroke
				(width 0.1)
				(type default)
			)
			(layer "F.Fab")
		)
		(fp_line
			(start 0.120396 0.2794)
			(end -0.12065 0.2794)
			(stroke
				(width 0.1)
				(type default)
			)
			(layer "F.Fab")
		)
		(fp_line
			(start -0.12065 0.3048)
			(end -0.67945 0.3048)
			(stroke
				(width 0.1)
				(type default)
			)
			(layer "F.Fab")
		)
		(fp_line
			(start -0.12065 0.2794)
			(end -0.12065 0.3048)
			(stroke
				(width 0.1)
				(type default)
			)
			(layer "F.Fab")
		)
		(fp_line
			(start -0.12065 -0.2794)
			(end 0.12065 -0.2794)
			(stroke
				(width 0.1)
				(type default)
			)
			(layer "F.Fab")
		)
		(fp_line
			(start -0.12065 -0.305054)
			(end -0.12065 -0.2794)
			(stroke
				(width 0.1)
				(type default)
			)
			(layer "F.Fab")
		)
		(fp_line
			(start -0.67945 0.3048)
			(end -0.67945 -0.305054)
			(stroke
				(width 0.1)
				(type default)
			)
			(layer "F.Fab")
		)
		(fp_line
			(start -0.67945 -0.305054)
			(end -0.12065 -0.305054)
			(stroke
				(width 0.1)
				(type default)
			)
			(layer "F.Fab")
		)
		(pad "1" smd circle
			(at -0.40005 0 180)
			(size 0 0)
			(layers "F.Cu" "F.Mask" "F.Paste")
			(net "P3V3_9ZXL045_P1_VDDR")
		)
		(pad "2" smd circle
			(at 0.40005 0 180)
			(size 0 0)
			(layers "F.Cu" "F.Mask" "F.Paste")
			(net "GND")
		)
	)
)
